(kicad_pcb
	(version 20260206)
	(generator "pcbnew")
	(generator_version "10.0")
	(general
		(thickness 1.6)
		(legacy_teardrops no)
	)
	(paper "A4")
	(title_block
		(title "04192023_DAF0TMB3IC0_F0TG_MB_C_brd_V02_OCP.brd")
		(comment 1 "Grand Teton / footprint 2835 of 8354 (J107), pads 1-48 of 48")
	)
	(layers
		(0 "F.Cu" signal "TOP")
		(4 "In1.Cu" signal "GND")
		(6 "In2.Cu" signal "IN1")
		(8 "In3.Cu" signal "GND1")
		(10 "In4.Cu" signal "IN2")
		(12 "In5.Cu" signal "GND2")
		(14 "In6.Cu" signal "IN3")
		(16 "In7.Cu" signal "GND3")
		(18 "In8.Cu" signal "VCC")
		(20 "In9.Cu" signal "VCC1")
		(22 "In10.Cu" signal "GND4")
		(24 "In11.Cu" signal "IN4")
		(26 "In12.Cu" signal "GND5")
		(28 "In13.Cu" signal "IN5")
		(30 "In14.Cu" signal "GND6")
		(32 "In15.Cu" signal "IN6")
		(34 "In16.Cu" signal "GND7")
		(2 "B.Cu" signal "BOTTOM")
		(9 "F.Adhes" user "F.Adhesive")
		(11 "B.Adhes" user "B.Adhesive")
		(13 "F.Paste" user "Package Geometry/Pastemask Top")
		(15 "B.Paste" user "Package Geometry/Pastemask Bottom")
		(5 "F.SilkS" user "Ref Des/Silkscreen Top")
		(7 "B.SilkS" user "Ref Des/Silkscreen Bottom")
		(1 "F.Mask" user "Board Geometry/Soldermask Top")
		(3 "B.Mask" user "Board Geometry/Soldermask Bottom")
		(17 "Dwgs.User" user "User.Drawings")
		(19 "Cmts.User" user "User.Comments")
		(21 "Eco1.User" user "User.Eco1")
		(23 "Eco2.User" user "User.Eco2")
		(25 "Edge.Cuts" user "Board Geometry/Outline")
		(27 "Margin" user)
		(31 "F.CrtYd" user "Package Geometry/Place Bound Top")
		(29 "B.CrtYd" user "Package Geometry/Place Bound Bottom")
		(35 "F.Fab" user "Ref Des/Assembly Top")
		(33 "B.Fab" user "Ref Des/Assembly Bottom")
	)
	(footprint ""
		(layer "F.Cu")
		(at 331.649832 -440.489848)
		(property "Reference" "J107"
			(at 19.92249 18.882106 0)
			(unlocked yes)
			(layer "F.SilkS")
			(effects
				(font
					(size 0.7874 0.5842)
					(thickness 0.1524)
				)
				(justify left)
			)
		)
		(property "Value" ""
			(at 0 0 0)
			(layer "F.Fab")
			(effects
				(font
					(size 1.27 1.27)
				)
			)
		)
		(duplicate_pad_numbers_are_jumpers no)
		(pad "A1" thru_hole rect
			(at 0 0 180)
			(size 0.766318 0.766318)
			(drill 0.359918)
			(layers "*.Cu" "*.Mask")
			(remove_unused_layers no)
			(net "NC_J107_A1")
			(clearance 0.0508)
			(thermal_gap 0.0508)
			(padstack
				(mode front_inner_back)
				(layer "Inner"
					(shape circle)
					(size 0.766318 0.766318)
					(clearance 0.0508)
				)
				(layer "B.Cu"
					(shape rect)
					(size 0.766318 0.766318)
					(clearance 0.0508)
				)
			)
		)
		(pad "A2" thru_hole circle
			(at 1.999996 0.199898 180)
			(size 0.906272 0.906272)
			(drill 0.499872)
			(layers "*.Cu" "*.Mask")
			(remove_unused_layers no)
			(net "GND")
			(clearance 0.0508)
			(thermal_gap 0.0508)
		)
		(pad "A3" thru_hole circle
			(at 3.999992 0 180)
			(size 0.766318 0.766318)
			(drill 0.359918)
			(layers "*.Cu" "*.Mask")
			(remove_unused_layers no)
			(net "NC_J107_A3")
			(clearance 0.0508)
			(thermal_gap 0.0508)
		)
		(pad "A4" thru_hole circle
			(at 5.999988 0.199898 180)
			(size 0.906272 0.906272)
			(drill 0.499872)
			(layers "*.Cu" "*.Mask")
			(remove_unused_layers no)
			(net "GND")
			(clearance 0.0508)
			(thermal_gap 0.0508)
		)
		(pad "A5" thru_hole circle
			(at 7.999984 0 180)
			(size 0.766318 0.766318)
			(drill 0.359918)
			(layers "*.Cu" "*.Mask")
			(remove_unused_layers no)
			(net "NC_J107_A5")
			(clearance 0.0508)
			(thermal_gap 0.0508)
		)
		(pad "A6" thru_hole circle
			(at 9.99998 0.199898 180)
			(size 0.906272 0.906272)
			(drill 0.499872)
			(layers "*.Cu" "*.Mask")
			(remove_unused_layers no)
			(net "GND")
			(clearance 0.0508)
			(thermal_gap 0.0508)
		)
		(pad "A7" thru_hole circle
			(at 11.999976 0 180)
			(size 0.766318 0.766318)
			(drill 0.359918)
			(layers "*.Cu" "*.Mask")
			(remove_unused_layers no)
			(net "SWB_HSC_PWRGD")
			(clearance 0.0508)
			(thermal_gap 0.0508)
		)
		(pad "A8" thru_hole circle
			(at 13.999972 0.199898 180)
			(size 0.906272 0.906272)
			(drill 0.499872)
			(layers "*.Cu" "*.Mask")
			(remove_unused_layers no)
			(net "GND")
			(clearance 0.0508)
			(thermal_gap 0.0508)
		)
		(pad "B1" thru_hole circle
			(at 0 1.199896 180)
			(size 0.906272 0.906272)
			(drill 0.499872)
			(layers "*.Cu" "*.Mask")
			(remove_unused_layers no)
			(net "GND")
			(clearance 0.0508)
			(thermal_gap 0.0508)
		)
		(pad "B3" thru_hole circle
			(at 3.999992 1.199896 180)
			(size 0.906272 0.906272)
			(drill 0.499872)
			(layers "*.Cu" "*.Mask")
			(remove_unused_layers no)
			(net "GND")
			(clearance 0.0508)
			(thermal_gap 0.0508)
		)
		(pad "B5" thru_hole circle
			(at 7.999984 1.199896 180)
			(size 0.906272 0.906272)
			(drill 0.499872)
			(layers "*.Cu" "*.Mask")
			(remove_unused_layers no)
			(net "GND")
			(clearance 0.0508)
			(thermal_gap 0.0508)
		)
		(pad "B7" thru_hole circle
			(at 11.999976 1.199896 180)
			(size 0.906272 0.906272)
			(drill 0.499872)
			(layers "*.Cu" "*.Mask")
			(remove_unused_layers no)
			(net "GND")
			(clearance 0.0508)
			(thermal_gap 0.0508)
		)
		(pad "D2" thru_hole circle
			(at 1.999996 3.800094 180)
			(size 0.906272 0.906272)
			(drill 0.499872)
			(layers "*.Cu" "*.Mask")
			(remove_unused_layers no)
			(net "GND")
			(clearance 0.0508)
			(thermal_gap 0.0508)
		)
		(pad "D4" thru_hole circle
			(at 5.999988 3.800094 180)
			(size 0.906272 0.906272)
			(drill 0.499872)
			(layers "*.Cu" "*.Mask")
			(remove_unused_layers no)
			(net "GND")
			(clearance 0.0508)
			(thermal_gap 0.0508)
		)
		(pad "D6" thru_hole circle
			(at 9.99998 3.800094 180)
			(size 0.906272 0.906272)
			(drill 0.499872)
			(layers "*.Cu" "*.Mask")
			(remove_unused_layers no)
			(net "GND")
			(clearance 0.0508)
			(thermal_gap 0.0508)
		)
		(pad "D8" thru_hole circle
			(at 13.999972 3.800094 180)
			(size 0.906272 0.906272)
			(drill 0.499872)
			(layers "*.Cu" "*.Mask")
			(remove_unused_layers no)
			(net "GND")
			(clearance 0.0508)
			(thermal_gap 0.0508)
		)
		(pad "E1" thru_hole circle
			(at 0 4.800092 180)
			(size 0.906272 0.906272)
			(drill 0.499872)
			(layers "*.Cu" "*.Mask")
			(remove_unused_layers no)
			(net "GND")
			(clearance 0.0508)
			(thermal_gap 0.0508)
		)
		(pad "E3" thru_hole circle
			(at 3.999992 4.800092 180)
			(size 0.906272 0.906272)
			(drill 0.499872)
			(layers "*.Cu" "*.Mask")
			(remove_unused_layers no)
			(net "GND")
			(clearance 0.0508)
			(thermal_gap 0.0508)
		)
		(pad "E5" thru_hole circle
			(at 7.999984 4.800092 180)
			(size 0.906272 0.906272)
			(drill 0.499872)
			(layers "*.Cu" "*.Mask")
			(remove_unused_layers no)
			(net "GND")
			(clearance 0.0508)
			(thermal_gap 0.0508)
		)
		(pad "E7" thru_hole circle
			(at 11.999976 4.800092 180)
			(size 0.906272 0.906272)
			(drill 0.499872)
			(layers "*.Cu" "*.Mask")
			(remove_unused_layers no)
			(net "GND")
			(clearance 0.0508)
			(thermal_gap 0.0508)
		)
		(pad "G2" thru_hole circle
			(at 1.999996 7.400036 180)
			(size 0.906272 0.906272)
			(drill 0.499872)
			(layers "*.Cu" "*.Mask")
			(remove_unused_layers no)
			(net "GND")
			(clearance 0.0508)
			(thermal_gap 0.0508)
		)
		(pad "G4" thru_hole circle
			(at 5.999988 7.400036 180)
			(size 0.906272 0.906272)
			(drill 0.499872)
			(layers "*.Cu" "*.Mask")
			(remove_unused_layers no)
			(net "GND")
			(clearance 0.0508)
			(thermal_gap 0.0508)
		)
		(pad "G6" thru_hole circle
			(at 9.99998 7.400036 180)
			(size 0.906272 0.906272)
			(drill 0.499872)
			(layers "*.Cu" "*.Mask")
			(remove_unused_layers no)
			(net "GND")
			(clearance 0.0508)
			(thermal_gap 0.0508)
		)
		(pad "G8" thru_hole circle
			(at 13.999972 7.400036 180)
			(size 0.906272 0.906272)
			(drill 0.499872)
			(layers "*.Cu" "*.Mask")
			(remove_unused_layers no)
			(net "GND")
			(clearance 0.0508)
			(thermal_gap 0.0508)
		)
		(pad "H1" thru_hole circle
			(at 0 8.400034 180)
			(size 0.906272 0.906272)
			(drill 0.499872)
			(layers "*.Cu" "*.Mask")
			(remove_unused_layers no)
			(net "GND")
			(clearance 0.0508)
			(thermal_gap 0.0508)
		)
		(pad "H3" thru_hole circle
			(at 3.999992 8.400034 180)
			(size 0.906272 0.906272)
			(drill 0.499872)
			(layers "*.Cu" "*.Mask")
			(remove_unused_layers no)
			(net "GND")
			(clearance 0.0508)
			(thermal_gap 0.0508)
		)
		(pad "H5" thru_hole circle
			(at 7.999984 8.400034 180)
			(size 0.906272 0.906272)
			(drill 0.499872)
			(layers "*.Cu" "*.Mask")
			(remove_unused_layers no)
			(net "GND")
			(clearance 0.0508)
			(thermal_gap 0.0508)
		)
		(pad "H7" thru_hole circle
			(at 11.999976 8.400034 180)
			(size 0.906272 0.906272)
			(drill 0.499872)
			(layers "*.Cu" "*.Mask")
			(remove_unused_layers no)
			(net "GND")
			(clearance 0.0508)
			(thermal_gap 0.0508)
		)
		(pad "J2" thru_hole circle
			(at 1.999996 10.999978 180)
			(size 0.906272 0.906272)
			(drill 0.499872)
			(layers "*.Cu" "*.Mask")
			(remove_unused_layers no)
			(net "GND")
			(clearance 0.0508)
			(thermal_gap 0.0508)
		)
		(pad "J4" thru_hole circle
			(at 5.999988 10.999978 180)
			(size 0.906272 0.906272)
			(drill 0.499872)
			(layers "*.Cu" "*.Mask")
			(remove_unused_layers no)
			(net "GND")
			(clearance 0.0508)
			(thermal_gap 0.0508)
		)
		(pad "J6" thru_hole circle
			(at 9.99998 10.999978 180)
			(size 0.906272 0.906272)
			(drill 0.499872)
			(layers "*.Cu" "*.Mask")
			(remove_unused_layers no)
			(net "GND")
			(clearance 0.0508)
			(thermal_gap 0.0508)
		)
		(pad "J8" thru_hole circle
			(at 13.999972 10.999978 180)
			(size 0.906272 0.906272)
			(drill 0.499872)
			(layers "*.Cu" "*.Mask")
			(remove_unused_layers no)
			(net "GND")
			(clearance 0.0508)
			(thermal_gap 0.0508)
		)
		(pad "K1" thru_hole circle
			(at 0 11.999976 180)
			(size 0.906272 0.906272)
			(drill 0.499872)
			(layers "*.Cu" "*.Mask")
			(remove_unused_layers no)
			(net "GND")
			(clearance 0.0508)
			(thermal_gap 0.0508)
		)
		(pad "K3" thru_hole circle
			(at 3.999992 11.999976 180)
			(size 0.906272 0.906272)
			(drill 0.499872)
			(layers "*.Cu" "*.Mask")
			(remove_unused_layers no)
			(net "GND")
			(clearance 0.0508)
			(thermal_gap 0.0508)
		)
		(pad "K5" thru_hole circle
			(at 7.999984 11.999976 180)
			(size 0.906272 0.906272)
			(drill 0.499872)
			(layers "*.Cu" "*.Mask")
			(remove_unused_layers no)
			(net "GND")
			(clearance 0.0508)
			(thermal_gap 0.0508)
		)
		(pad "K7" thru_hole circle
			(at 11.999976 11.999976 180)
			(size 0.906272 0.906272)
			(drill 0.499872)
			(layers "*.Cu" "*.Mask")
			(remove_unused_layers no)
			(net "GND")
			(clearance 0.0508)
			(thermal_gap 0.0508)
		)
		(pad "M2" thru_hole circle
			(at 1.999996 14.59992 180)
			(size 0.906272 0.906272)
			(drill 0.499872)
			(layers "*.Cu" "*.Mask")
			(remove_unused_layers no)
			(net "GND")
			(clearance 0.0508)
			(thermal_gap 0.0508)
		)
		(pad "M4" thru_hole circle
			(at 5.999988 14.59992 180)
			(size 0.906272 0.906272)
			(drill 0.499872)
			(layers "*.Cu" "*.Mask")
			(remove_unused_layers no)
			(net "GND")
			(clearance 0.0508)
			(thermal_gap 0.0508)
		)
		(pad "M6" thru_hole circle
			(at 9.99998 14.59992 180)
			(size 0.906272 0.906272)
			(drill 0.499872)
			(layers "*.Cu" "*.Mask")
			(remove_unused_layers no)
			(net "GND")
			(clearance 0.0508)
			(thermal_gap 0.0508)
		)
		(pad "M8" thru_hole circle
			(at 13.999972 14.59992 180)
			(size 0.906272 0.906272)
			(drill 0.499872)
			(layers "*.Cu" "*.Mask")
			(remove_unused_layers no)
			(net "GND")
			(clearance 0.0508)
			(thermal_gap 0.0508)
		)
		(pad "N1" thru_hole circle
			(at 0 15.599918 180)
			(size 0.906272 0.906272)
			(drill 0.499872)
			(layers "*.Cu" "*.Mask")
			(remove_unused_layers no)
			(net "GND")
			(clearance 0.0508)
			(thermal_gap 0.0508)
		)
		(pad "N2" thru_hole circle
			(at 1.999996 15.80007 180)
			(size 0.766318 0.766318)
			(drill 0.359918)
			(layers "*.Cu" "*.Mask")
			(remove_unused_layers no)
			(net "PRSNT_CABLE_SWB_B2_N")
			(clearance 0.0508)
			(thermal_gap 0.0508)
		)
		(pad "N3" thru_hole circle
			(at 3.999992 15.599918 180)
			(size 0.906272 0.906272)
			(drill 0.499872)
			(layers "*.Cu" "*.Mask")
			(remove_unused_layers no)
			(net "GND")
			(clearance 0.0508)
			(thermal_gap 0.0508)
		)
		(pad "N4" thru_hole circle
			(at 5.999988 15.80007 180)
			(size 0.766318 0.766318)
			(drill 0.359918)
			(layers "*.Cu" "*.Mask")
			(remove_unused_layers no)
			(net "NC_J107_N4")
			(clearance 0.0508)
			(thermal_gap 0.0508)
		)
		(pad "N5" thru_hole circle
			(at 7.999984 15.599918 180)
			(size 0.906272 0.906272)
			(drill 0.499872)
			(layers "*.Cu" "*.Mask")
			(remove_unused_layers no)
			(net "GND")
			(clearance 0.0508)
			(thermal_gap 0.0508)
		)
		(pad "N6" thru_hole circle
			(at 9.99998 15.80007 180)
			(size 0.766318 0.766318)
			(drill 0.359918)
			(layers "*.Cu" "*.Mask")
			(remove_unused_layers no)
			(net "NC_J107_N6")
			(clearance 0.0508)
			(thermal_gap 0.0508)
		)
		(pad "N7" thru_hole circle
			(at 11.999976 15.599918 180)
			(size 0.906272 0.906272)
			(drill 0.499872)
			(layers "*.Cu" "*.Mask")
			(remove_unused_layers no)
			(net "GND")
			(clearance 0.0508)
			(thermal_gap 0.0508)
		)
		(pad "N8" thru_hole circle
			(at 13.999972 15.80007 180)
			(size 0.766318 0.766318)
			(drill 0.359918)
			(layers "*.Cu" "*.Mask")
			(remove_unused_layers no)
			(net "SWB_HSC_EN_BUF")
			(clearance 0.0508)
			(thermal_gap 0.0508)
		)
	)
)
